# TIMECARD (Time Appliance Project (Time Card)) — schematic netlist excerpt (pin names and nets, part order shuffled) for the footprints in the layout excerpt that follows; sources: Cadence DE-HDL packaged netlist, KiCad conversion of R4006-B0001-02_R01.brd

R220  RESISTOR  1KOHM 1%  pkg SMC_0402R_H016  page 10 : \1\ = FPGA_BRD_REV0 ; \2\ = SG
R206  RESISTOR  33OHM 1%  pkg SMC_0402R_H016  page 10 : \1\ = UNNAMED_127_MT25QL128ABA1ESES_2 ; \2\ = FLASH_DQ3

(kicad_pcb
	(version 20260206)
	(generator "pcbnew")
	(generator_version "10.0")
	(general
		(thickness 1.6)
		(legacy_teardrops no)
	)
	(paper "A4")
	(title_block
		(title "timecard-production-celestica-r4006 — R4006-B0001-02_R01.brd")
		(comment 1 "Time Appliance Project (Time Card) / footprints 970-971 of 1113")
	)
	(layers
		(0 "F.Cu" signal "TOP")
		(4 "In1.Cu" signal "L02_GND1")
		(6 "In2.Cu" signal "L03_SIG1")
		(8 "In3.Cu" signal "L04_GND2")
		(10 "In4.Cu" signal "L05_VCC1")
		(12 "In5.Cu" signal "L06_VCC2")
		(14 "In6.Cu" signal "L07_GND3")
		(16 "In7.Cu" signal "L08_SIG2")
		(18 "In8.Cu" signal "L09_GND4")
		(2 "B.Cu" signal "BOTTOM")
		(9 "F.Adhes" user "F.Adhesive")
		(11 "B.Adhes" user "B.Adhesive")
		(13 "F.Paste" user "Package Geometry/Pastemask Top")
		(15 "B.Paste" user "Package Geometry/Pastemask Bottom")
		(5 "F.SilkS" user "Ref Des/Silkscreen Top")
		(7 "B.SilkS" user "Ref Des/Silkscreen Bottom")
		(1 "F.Mask" user "Board Geometry/Soldermask Top")
		(3 "B.Mask" user "Board Geometry/Soldermask Bottom")
		(17 "Dwgs.User" user "User.Drawings")
		(19 "Cmts.User" user "User.Comments")
		(21 "Eco1.User" user "User.Eco1")
		(23 "Eco2.User" user "User.Eco2")
		(25 "Edge.Cuts" user "Board Geometry/Outline")
		(27 "Margin" user)
		(31 "F.CrtYd" user "Package Geometry/Place Bound Top")
		(29 "B.CrtYd" user "Package Geometry/Place Bound Bottom")
		(35 "F.Fab" user "Ref Des/Assembly Top")
		(33 "B.Fab" user "Ref Des/Assembly Bottom")
	)
	(footprint ""
		(layer "B.Cu")
		(at 112.776 -61.976 -90)
		(property "Reference" "R220"
			(at -3.302 0.03937 270)
			(unlocked yes)
			(layer "B.SilkS")
			(effects
				(font
					(size 0.7874 0.5842)
					(thickness 0.1524)
				)
				(justify mirror)
			)
		)
		(property "Value" "VAL*"
			(at -0.02032 2.13233 270)
			(unlocked yes)
			(layer "B.Fab")
			(hide yes)
			(effects
				(font
					(size 0.7874 0.5842)
					(thickness 0.1524)
				)
				(justify mirror)
			)
		)
		(property "Device Type" "RESISTOR-G155-11001-01,1KOHM,1%"
			(at -0.008382 1.210564 270)
			(unlocked yes)
			(layer "B.Fab")
			(hide yes)
			(effects
				(font
					(size 0.7874 0.5842)
					(thickness 0.1524)
				)
				(justify mirror)
			)
		)
		(property "User Part Number" "PARTNUM*"
			(at -0.02032 4.024884 270)
			(unlocked yes)
			(layer "Cmts.User")
			(hide yes)
			(effects
				(font
					(size 0.7874 0.5842)
					(thickness 0.1524)
				)
				(justify mirror)
			)
		)
		(property "Tolerance" "TOL*"
			(at -0.044704 3.05435 270)
			(unlocked yes)
			(layer "Cmts.User")
			(hide yes)
			(effects
				(font
					(size 0.7874 0.5842)
					(thickness 0.1524)
				)
				(justify mirror)
			)
		)
		(duplicate_pad_numbers_are_jumpers no)
		(fp_line
			(start -1.143 0.5588)
			(end -1.143 -0.5588)
			(stroke
				(width 0.1)
				(type default)
			)
			(layer "B.SilkS")
		)
		(fp_line
			(start 1.143 0.5588)
			(end -1.143 0.5588)
			(stroke
				(width 0.1)
				(type default)
			)
			(layer "B.SilkS")
		)
		(fp_line
			(start -1.143 -0.5588)
			(end 1.143 -0.5588)
			(stroke
				(width 0.1)
				(type default)
			)
			(layer "B.SilkS")
		)
		(fp_line
			(start 1.143 -0.5588)
			(end 1.143 0.5588)
			(stroke
				(width 0.1)
				(type default)
			)
			(layer "B.SilkS")
		)
		(fp_rect
			(start 1.143 0.5588)
			(end -1.143 -0.5588)
			(stroke
				(width 0)
				(type default)
			)
			(fill no)
			(layer "B.CrtYd")
		)
		(fp_line
			(start -0.508 0.3048)
			(end -0.508 -0.3048)
			(stroke
				(width 0.1)
				(type default)
			)
			(layer "B.Fab")
		)
		(fp_line
			(start 0.508 0.3048)
			(end -0.508 0.3048)
			(stroke
				(width 0.1)
				(type default)
			)
			(layer "B.Fab")
		)
		(fp_line
			(start -0.508 -0.3048)
			(end 0.508 -0.3048)
			(stroke
				(width 0.1)
				(type default)
			)
			(layer "B.Fab")
		)
		(fp_line
			(start 0.508 -0.3048)
			(end 0.508 0.3048)
			(stroke
				(width 0.1)
				(type default)
			)
			(layer "B.Fab")
		)
		(pad "1" smd rect
			(at 0.5334 0 90)
			(size 0.7112 0.6096)
			(layers "B.Cu" "B.Mask" "B.Paste")
			(net "FPGA_BRD_REV0")
		)
		(pad "2" smd rect
			(at -0.5334 0 90)
			(size 0.7112 0.6096)
			(layers "B.Cu" "B.Mask" "B.Paste")
			(net "SG")
		)
		(zone
			(layer "B.Cu")
			(hatch none 0.5)
			(connect_pads
				(clearance 0)
			)
			(min_thickness 0.25)
			(keepout
				(tracks allowed)
				(vias not_allowed)
				(pads allowed)
				(copperpour not_allowed)
				(footprints allowed)
			)
			(placement
				(enabled no)
				(sheetname "")
			)
			(fill
				(thermal_gap 0.5)
				(thermal_bridge_width 0.5)
				(island_removal_mode 0)
			)
			(polygon
				(pts
					(xy 112.4712 -61.8998) (xy 113.0808 -61.8998) (xy 113.0808 -62.0522) (xy 112.4712 -62.0522)
				)
			)
		)
	)
	(footprint ""
		(layer "B.Cu")
		(at 88.519 -82.169 180)
		(property "Reference" "R206"
			(at -0.254 5.67563 0)
			(unlocked yes)
			(layer "B.SilkS")
			(effects
				(font
					(size 0.7874 0.5842)
					(thickness 0.1524)
				)
				(justify mirror)
			)
		)
		(property "Value" "VAL*"
			(at -0.02032 2.13233 180)
			(unlocked yes)
			(layer "B.Fab")
			(hide yes)
			(effects
				(font
					(size 0.7874 0.5842)
					(thickness 0.1524)
				)
				(justify mirror)
			)
		)
		(property "Device Type" "RESISTOR-G155-133R0-01,33OHM,1%"
			(at -0.008382 1.210564 180)
			(unlocked yes)
			(layer "B.Fab")
			(hide yes)
			(effects
				(font
					(size 0.7874 0.5842)
					(thickness 0.1524)
				)
				(justify mirror)
			)
		)
		(property "User Part Number" "PARTNUM*"
			(at -0.02032 4.024884 180)
			(unlocked yes)
			(layer "Cmts.User")
			(hide yes)
			(effects
				(font
					(size 0.7874 0.5842)
					(thickness 0.1524)
				)
				(justify mirror)
			)
		)
		(property "Tolerance" "TOL*"
			(at -0.044704 3.05435 180)
			(unlocked yes)
			(layer "Cmts.User")
			(hide yes)
			(effects
				(font
					(size 0.7874 0.5842)
					(thickness 0.1524)
				)
				(justify mirror)
			)
		)
		(duplicate_pad_numbers_are_jumpers no)
		(fp_line
			(start 1.143 0.5588)
			(end -1.143 0.5588)
			(stroke
				(width 0.1)
				(type default)
			)
			(layer "B.SilkS")
		)
		(fp_line
			(start 1.143 -0.5588)
			(end 1.143 0.5588)
			(stroke
				(width 0.1)
				(type default)
			)
			(layer "B.SilkS")
		)
		(fp_line
			(start -1.143 0.5588)
			(end -1.143 -0.5588)
			(stroke
				(width 0.1)
				(type default)
			)
			(layer "B.SilkS")
		)
		(fp_line
			(start -1.143 -0.5588)
			(end 1.143 -0.5588)
			(stroke
				(width 0.1)
				(type default)
			)
			(layer "B.SilkS")
		)
		(fp_rect
			(start 1.143 -0.5588)
			(end -1.143 0.5588)
			(stroke
				(width 0)
				(type default)
			)
			(fill no)
			(layer "B.CrtYd")
		)
		(fp_line
			(start 0.508 0.3048)
			(end -0.508 0.3048)
			(stroke
				(width 0.1)
				(type default)
			)
			(layer "B.Fab")
		)
		(fp_line
			(start 0.508 -0.3048)
			(end 0.508 0.3048)
			(stroke
				(width 0.1)
				(type default)
			)
			(layer "B.Fab")
		)
		(fp_line
			(start -0.508 0.3048)
			(end -0.508 -0.3048)
			(stroke
				(width 0.1)
				(type default)
			)
			(layer "B.Fab")
		)
		(fp_line
			(start -0.508 -0.3048)
			(end 0.508 -0.3048)
			(stroke
				(width 0.1)
				(type default)
			)
			(layer "B.Fab")
		)
		(pad "1" smd rect
			(at 0.5334 0)
			(size 0.7112 0.6096)
			(layers "B.Cu" "B.Mask" "B.Paste")
			(net "UNNAMED_127_MT25QL128ABA1ESES_2")
		)
		(pad "2" smd rect
			(at -0.5334 0)
			(size 0.7112 0.6096)
			(layers "B.Cu" "B.Mask" "B.Paste")
			(net "FLASH_DQ3")
		)
		(zone
			(layer "B.Cu")
			(hatch none 0.5)
			(connect_pads
				(clearance 0)
			)
			(min_thickness 0.25)
			(keepout
				(tracks allowed)
				(vias not_allowed)
				(pads allowed)
				(copperpour not_allowed)
				(footprints allowed)
			)
			(placement
				(enabled no)
				(sheetname "")
			)
			(fill
				(thermal_gap 0.5)
				(thermal_bridge_width 0.5)
				(island_removal_mode 0)
			)
			(polygon
				(pts
					(xy 88.4428 -81.8642) (xy 88.5952 -81.8642) (xy 88.5952 -82.4738) (xy 88.4428 -82.4738)
				)
			)
		)
	)
)
